# T6G (Grand Teton) — schematic netlist excerpt (pin names and nets, part order shuffled) for the footprints in the layout excerpt that follows; sources: Cadence DE-HDL packaged netlist, KiCad conversion of 04192023_DAF0TMB3IC0_F0TG_MB_C_brd_V02_OCP.brd

PC601  Q_CAPP  470UF 2.5V 20% SPCAP  pkg SMLF  page 198 : A = PVDDCR_SOC_P0 ; B = GND
C1006  Q_CAP  1UF 4V 20% X6S  pkg 0201  page 312 : A = P0V9_CPU0_RT3_2A ; B = GND
R6100  Q_RES  49.9 1% CHIP  pkg 0402LF  page 34 : A = FM_BIOS_POST_CMPLT_BUF_R1_N ; B = FM_BIOS_POST_CMPLT_BUF_N

(kicad_pcb
	(version 20260206)
	(generator "pcbnew")
	(generator_version "10.0")
	(general
		(thickness 1.6)
		(legacy_teardrops no)
	)
	(paper "A4")
	(title_block
		(title "04192023_DAF0TMB3IC0_F0TG_MB_C_brd_V02_OCP.brd")
		(comment 1 "Grand Teton / footprints 7908-7910 of 8354")
	)
	(layers
		(0 "F.Cu" signal "TOP")
		(4 "In1.Cu" signal "GND")
		(6 "In2.Cu" signal "IN1")
		(8 "In3.Cu" signal "GND1")
		(10 "In4.Cu" signal "IN2")
		(12 "In5.Cu" signal "GND2")
		(14 "In6.Cu" signal "IN3")
		(16 "In7.Cu" signal "GND3")
		(18 "In8.Cu" signal "VCC")
		(20 "In9.Cu" signal "VCC1")
		(22 "In10.Cu" signal "GND4")
		(24 "In11.Cu" signal "IN4")
		(26 "In12.Cu" signal "GND5")
		(28 "In13.Cu" signal "IN5")
		(30 "In14.Cu" signal "GND6")
		(32 "In15.Cu" signal "IN6")
		(34 "In16.Cu" signal "GND7")
		(2 "B.Cu" signal "BOTTOM")
		(9 "F.Adhes" user "F.Adhesive")
		(11 "B.Adhes" user "B.Adhesive")
		(13 "F.Paste" user "Package Geometry/Pastemask Top")
		(15 "B.Paste" user "Package Geometry/Pastemask Bottom")
		(5 "F.SilkS" user "Ref Des/Silkscreen Top")
		(7 "B.SilkS" user "Ref Des/Silkscreen Bottom")
		(1 "F.Mask" user "Board Geometry/Soldermask Top")
		(3 "B.Mask" user "Board Geometry/Soldermask Bottom")
		(17 "Dwgs.User" user "User.Drawings")
		(19 "Cmts.User" user "User.Comments")
		(21 "Eco1.User" user "User.Eco1")
		(23 "Eco2.User" user "User.Eco2")
		(25 "Edge.Cuts" user "Board Geometry/Outline")
		(27 "Margin" user)
		(31 "F.CrtYd" user "Package Geometry/Place Bound Top")
		(29 "B.CrtYd" user "Package Geometry/Place Bound Bottom")
		(35 "F.Fab" user "Ref Des/Assembly Top")
		(33 "B.Fab" user "Ref Des/Assembly Bottom")
	)
	(footprint ""
		(layer "B.Cu")
		(at 398.502124 -344.850212 -90)
		(property "Reference" "R6100"
			(at 0 0 90)
			(layer "B.SilkS")
			(hide yes)
			(effects
				(font
					(size 1.27 1.27)
				)
				(justify mirror)
			)
		)
		(property "Value" ""
			(at 0 0 90)
			(layer "B.Fab")
			(effects
				(font
					(size 1.27 1.27)
				)
				(justify mirror)
			)
		)
		(duplicate_pad_numbers_are_jumpers no)
		(fp_line
			(start -0.7874 0.4064)
			(end 0.7874 0.4064)
			(stroke
				(width 0.1524)
				(type default)
			)
			(layer "B.SilkS")
		)
		(fp_line
			(start 0.7874 0.4064)
			(end 0.7874 -0.4064)
			(stroke
				(width 0.1524)
				(type default)
			)
			(layer "B.SilkS")
		)
		(fp_line
			(start -0.7874 -0.4064)
			(end -0.7874 0.4064)
			(stroke
				(width 0.1524)
				(type default)
			)
			(layer "B.SilkS")
		)
		(fp_line
			(start 0.7874 -0.4064)
			(end -0.7874 -0.4064)
			(stroke
				(width 0.1524)
				(type default)
			)
			(layer "B.SilkS")
		)
		(fp_line
			(start -0.67945 0.3048)
			(end -0.120396 0.3048)
			(stroke
				(width 0.1)
				(type default)
			)
			(layer "B.Fab")
		)
		(fp_line
			(start -0.120396 0.3048)
			(end -0.120396 0.2794)
			(stroke
				(width 0.1)
				(type default)
			)
			(layer "B.Fab")
		)
		(fp_line
			(start 0.12065 0.3048)
			(end 0.67945 0.3048)
			(stroke
				(width 0.1)
				(type default)
			)
			(layer "B.Fab")
		)
		(fp_line
			(start 0.67945 0.3048)
			(end 0.67945 -0.305054)
			(stroke
				(width 0.1)
				(type default)
			)
			(layer "B.Fab")
		)
		(fp_line
			(start -0.120396 0.2794)
			(end 0.12065 0.2794)
			(stroke
				(width 0.1)
				(type default)
			)
			(layer "B.Fab")
		)
		(fp_line
			(start 0.12065 0.2794)
			(end 0.12065 0.3048)
			(stroke
				(width 0.1)
				(type default)
			)
			(layer "B.Fab")
		)
		(fp_line
			(start -0.12065 -0.2794)
			(end -0.12065 -0.3048)
			(stroke
				(width 0.1)
				(type default)
			)
			(layer "B.Fab")
		)
		(fp_line
			(start 0.12065 -0.2794)
			(end -0.12065 -0.2794)
			(stroke
				(width 0.1)
				(type default)
			)
			(layer "B.Fab")
		)
		(fp_line
			(start -0.67945 -0.3048)
			(end -0.67945 0.3048)
			(stroke
				(width 0.1)
				(type default)
			)
			(layer "B.Fab")
		)
		(fp_line
			(start -0.12065 -0.3048)
			(end -0.67945 -0.3048)
			(stroke
				(width 0.1)
				(type default)
			)
			(layer "B.Fab")
		)
		(fp_line
			(start 0.12065 -0.305054)
			(end 0.12065 -0.2794)
			(stroke
				(width 0.1)
				(type default)
			)
			(layer "B.Fab")
		)
		(fp_line
			(start 0.67945 -0.305054)
			(end 0.12065 -0.305054)
			(stroke
				(width 0.1)
				(type default)
			)
			(layer "B.Fab")
		)
		(pad "1" smd circle
			(at 0.40005 0 90)
			(size 0 0)
			(layers "B.Cu" "B.Mask" "B.Paste")
			(net "FM_BIOS_POST_CMPLT_BUF_R1_N")
		)
		(pad "2" smd circle
			(at -0.40005 0 90)
			(size 0 0)
			(layers "B.Cu" "B.Mask" "B.Paste")
			(net "FM_BIOS_POST_CMPLT_BUF_N")
		)
	)
	(footprint ""
		(layer "B.Cu")
		(at 397.876014 -183.888888 90)
		(property "Reference" "PC601"
			(at 6.967728 0.110998 270)
			(unlocked yes)
			(layer "B.SilkS")
			(effects
				(font
					(size 0.7874 0.5842)
					(thickness 0.1524)
				)
				(justify left mirror)
			)
		)
		(property "Value" ""
			(at 0 0 90)
			(layer "B.Fab")
			(effects
				(font
					(size 1.27 1.27)
				)
				(justify mirror)
			)
		)
		(duplicate_pad_numbers_are_jumpers no)
		(fp_line
			(start 4.533392 -2.249932)
			(end -4.533392 -2.249932)
			(stroke
				(width 0.1524)
				(type default)
			)
			(layer "B.SilkS")
		)
		(fp_line
			(start -4.533392 -2.249932)
			(end -4.533392 2.249932)
			(stroke
				(width 0.1524)
				(type default)
			)
			(layer "B.SilkS")
		)
		(fp_line
			(start 4.533392 2.249932)
			(end 4.533392 -2.249932)
			(stroke
				(width 0.1524)
				(type default)
			)
			(layer "B.SilkS")
		)
		(fp_line
			(start -4.533392 2.249932)
			(end 4.533392 2.249932)
			(stroke
				(width 0.1524)
				(type default)
			)
			(layer "B.SilkS")
		)
		(fp_rect
			(start 4.533392 -2.326132)
			(end 5.39242 2.326132)
			(stroke
				(width 0)
				(type default)
			)
			(fill yes)
			(layer "B.SilkS")
		)
		(fp_line
			(start 3.750056 -2.249932)
			(end -3.750056 -2.249932)
			(stroke
				(width 0.1)
				(type default)
			)
			(layer "B.Fab")
		)
		(fp_line
			(start -3.750056 -2.249932)
			(end -3.750056 2.249932)
			(stroke
				(width 0.1)
				(type default)
			)
			(layer "B.Fab")
		)
		(fp_line
			(start 3.750056 2.249932)
			(end 3.750056 -2.249932)
			(stroke
				(width 0.1)
				(type default)
			)
			(layer "B.Fab")
		)
		(fp_line
			(start -3.750056 2.249932)
			(end 3.750056 2.249932)
			(stroke
				(width 0.1)
				(type default)
			)
			(layer "B.Fab")
		)
		(fp_text user "-"
			(at -4.8514 -0.14605 90)
			(unlocked yes)
			(layer "B.SilkS")
			(effects
				(font
					(size 1.905 1.4224)
					(thickness 0.1524)
				)
				(justify left mirror)
			)
		)
		(fp_text user "+"
			(at 6.322314 0.786384 0)
			(unlocked yes)
			(layer "B.SilkS")
			(effects
				(font
					(size 1.905 1.4224)
					(thickness 0.1524)
				)
				(justify left mirror)
			)
		)
		(fp_text user "-"
			(at -4.8514 -0.14605 90)
			(unlocked yes)
			(layer "B.Fab")
			(effects
				(font
					(size 1.905 1.4224)
					(thickness 0.1524)
				)
				(justify left mirror)
			)
		)
		(fp_text user "+"
			(at 6.322314 0.786384 0)
			(unlocked yes)
			(layer "B.Fab")
			(effects
				(font
					(size 1.905 1.4224)
					(thickness 0.1524)
				)
				(justify left mirror)
			)
		)
		(pad "1" smd rect
			(at 3.199892 0 270)
			(size 2.413 2.8194)
			(layers "B.Cu" "B.Mask" "B.Paste")
			(net "PVDDCR_SOC_P0")
		)
		(pad "2" smd rect
			(at -3.199892 0 270)
			(size 2.413 2.8194)
			(layers "B.Cu" "B.Mask" "B.Paste")
			(net "GND")
		)
	)
	(footprint ""
		(layer "B.Cu")
		(at 370.272818 -393.88288 -90)
		(property "Reference" "C1006"
			(at 0 0 90)
			(layer "B.SilkS")
			(hide yes)
			(effects
				(font
					(size 1.27 1.27)
				)
				(justify mirror)
			)
		)
		(property "Value" ""
			(at 0 0 90)
			(layer "B.Fab")
			(effects
				(font
					(size 1.27 1.27)
				)
				(justify mirror)
			)
		)
		(duplicate_pad_numbers_are_jumpers no)
		(fp_line
			(start -0.299974 0.150114)
			(end 0.299974 0.150114)
			(stroke
				(width 0.1)
				(type default)
			)
			(layer "B.Fab")
		)
		(fp_line
			(start 0.299974 0.150114)
			(end 0.299974 -0.150114)
			(stroke
				(width 0.1)
				(type default)
			)
			(layer "B.Fab")
		)
		(fp_line
			(start -0.299974 -0.150114)
			(end -0.299974 0.150114)
			(stroke
				(width 0.1)
				(type default)
			)
			(layer "B.Fab")
		)
		(fp_line
			(start 0.299974 -0.150114)
			(end -0.299974 -0.150114)
			(stroke
				(width 0.1)
				(type default)
			)
			(layer "B.Fab")
		)
		(pad "1" smd rect
			(at 0.2667 0 90)
			(size 0.3048 0.381)
			(layers "B.Cu" "B.Mask" "B.Paste")
			(net "P0V9_CPU0_RT3_2A")
		)
		(pad "2" smd rect
			(at -0.2667 0 90)
			(size 0.3048 0.381)
			(layers "B.Cu" "B.Mask" "B.Paste")
			(net "GND")
		)
	)
)
